(kicad_pcb
	(version 20260206)
	(generator "pcbnew")
	(generator_version "10.0")
	(general
		(thickness 1.6)
		(legacy_teardrops no)
	)
	(paper "A4")
	(title_block
		(title "Bryce Canyon_F.DPB_16315-1-OCP.brd")
		(comment 1 "Bryce Canyon / footprints 713-718 of 2223")
	)
	(layers
		(0 "F.Cu" signal "TOP")
		(4 "In1.Cu" signal "L2GND")
		(6 "In2.Cu" signal "L3")
		(8 "In3.Cu" signal "L4GND")
		(10 "In4.Cu" signal "L5")
		(12 "In5.Cu" signal "L6VCC")
		(14 "In6.Cu" signal "L7VCC")
		(16 "In7.Cu" signal "L8")
		(18 "In8.Cu" signal "L9GND")
		(20 "In9.Cu" signal "L10")
		(22 "In10.Cu" signal "L11GND")
		(2 "B.Cu" signal "BOTTOM")
		(9 "F.Adhes" user "F.Adhesive")
		(11 "B.Adhes" user "B.Adhesive")
		(13 "F.Paste" user "Package Geometry/Pastemask Top")
		(15 "B.Paste" user "Package Geometry/Pastemask Bottom")
		(5 "F.SilkS" user "Ref Des/Silkscreen Top")
		(7 "B.SilkS" user "Ref Des/Silkscreen Bottom")
		(1 "F.Mask" user "Board Geometry/Soldermask Top")
		(3 "B.Mask" user "Board Geometry/Soldermask Bottom")
		(17 "Dwgs.User" user "User.Drawings")
		(19 "Cmts.User" user "User.Comments")
		(21 "Eco1.User" user "User.Eco1")
		(23 "Eco2.User" user "User.Eco2")
		(25 "Edge.Cuts" user "Board Geometry/Outline")
		(27 "Margin" user)
		(31 "F.CrtYd" user "Package Geometry/Place Bound Top")
		(29 "B.CrtYd" user "Package Geometry/Place Bound Bottom")
		(35 "F.Fab" user "Ref Des/Assembly Top")
		(33 "B.Fab" user "Ref Des/Assembly Bottom")
	)
	(footprint ""
		(layer "F.Cu")
		(at 461.9371 -275.735542 180)
		(property "Reference" "R377"
			(at 0 0 180)
			(layer "F.SilkS")
			(hide yes)
			(effects
				(font
					(size 1.27 1.27)
				)
			)
		)
		(property "Value" "0R2J-2-GP"
			(at 0.064008 -3.993896 180)
			(unlocked yes)
			(layer "F.Fab")
			(hide yes)
			(effects
				(font
					(size 1.016 1.016)
					(thickness 0.1524)
				)
			)
		)
		(property "Device Type" "R402H16"
			(at 0.064008 -5.517896 180)
			(unlocked yes)
			(layer "F.Fab")
			(hide yes)
			(effects
				(font
					(size 1.016 1.016)
					(thickness 0.1524)
				)
			)
		)
		(duplicate_pad_numbers_are_jumpers no)
		(fp_line
			(start 0.508 -0.9398)
			(end -0.508 -0.9398)
			(stroke
				(width 0.1524)
				(type default)
			)
			(layer "F.SilkS")
		)
		(fp_line
			(start -0.508 -0.9398)
			(end -0.508 0.9398)
			(stroke
				(width 0.1524)
				(type default)
			)
			(layer "F.SilkS")
		)
		(fp_rect
			(start -0.508 0.9398)
			(end 0.508 -0.9398)
			(stroke
				(width 0)
				(type default)
			)
			(fill no)
			(layer "F.CrtYd")
		)
		(fp_rect
			(start -0.508 0.9398)
			(end 0.508 -0.9398)
			(stroke
				(width 0)
				(type default)
			)
			(fill no)
			(layer "F.Fab")
		)
		(pad "1" smd custom
			(at 0 -0.4445 180)
			(size 0.1397 0.1397)
			(layers "F.Cu" "F.Mask" "F.Paste")
			(net "SW_HDD_G10")
			(options
				(clearance outline)
				(anchor circle)
			)
			(primitives
				(gr_poly
					(pts
						(arc
							(start -0.1778 -0.2794)
							(mid -0.249642 -0.249642)
							(end -0.2794 -0.1778)
						)
						(arc
							(start -0.2794 0.1778)
							(mid -0.249642 0.249642)
							(end -0.1778 0.2794)
						)
						(arc
							(start 0.1778 0.2794)
							(mid 0.249642 0.249642)
							(end 0.2794 0.1778)
						)
						(arc
							(start 0.2794 -0.1778)
							(mid 0.249642 -0.249642)
							(end 0.1778 -0.2794)
						)
					)
					(width 0)
					(fill yes)
				)
			)
		)
		(pad "2" smd custom
			(at 0 0.4445 180)
			(size 0.1397 0.1397)
			(layers "F.Cu" "F.Mask" "F.Paste")
			(net "SW_HDD_R10")
			(options
				(clearance outline)
				(anchor circle)
			)
			(primitives
				(gr_poly
					(pts
						(arc
							(start -0.1778 -0.2794)
							(mid -0.249642 -0.249642)
							(end -0.2794 -0.1778)
						)
						(arc
							(start -0.2794 0.1778)
							(mid -0.249642 0.249642)
							(end -0.1778 0.2794)
						)
						(arc
							(start 0.1778 0.2794)
							(mid 0.249642 0.249642)
							(end 0.2794 0.1778)
						)
						(arc
							(start 0.2794 -0.1778)
							(mid 0.249642 -0.249642)
							(end 0.1778 -0.2794)
						)
					)
					(width 0)
					(fill yes)
				)
			)
		)
	)
	(footprint ""
		(layer "F.Cu")
		(at 383.3368 -46.1518)
		(property "Reference" "VIA13"
			(at 0 0 0)
			(layer "F.SilkS")
			(hide yes)
			(effects
				(font
					(size 1.27 1.27)
				)
			)
		)
		(property "Value" "100OHM-8L-1D6MM-L18L16-GP"
			(at -3.7211 -4.5085 0)
			(unlocked yes)
			(layer "F.Fab")
			(hide yes)
			(effects
				(font
					(size 1.016 1.016)
					(thickness 0.1524)
				)
			)
		)
		(property "Device Type" "VIA-PCIE-4P-394076"
			(at -3.7211 -6.0325 0)
			(unlocked yes)
			(layer "F.Fab")
			(hide yes)
			(effects
				(font
					(size 1.016 1.016)
					(thickness 0.1524)
				)
			)
		)
		(duplicate_pad_numbers_are_jumpers no)
		(fp_rect
			(start -1.9685 0.381)
			(end 1.9685 -0.381)
			(stroke
				(width 0)
				(type default)
			)
			(fill no)
			(layer "F.CrtYd")
		)
		(fp_rect
			(start -1.9685 0.381)
			(end 1.9685 -0.381)
			(stroke
				(width 0)
				(type default)
			)
			(fill no)
			(layer "F.Fab")
		)
		(pad "1" thru_hole circle
			(at -1.5875 0)
			(size 0.508 0.508)
			(drill 0.254)
			(layers "*.Cu" "*.Mask")
			(remove_unused_layers no)
			(net "GND")
			(clearance 0.127)
			(thermal_gap 0.127)
		)
		(pad "2" thru_hole circle
			(at -0.5715 0)
			(size 0.508 0.508)
			(drill 0.254)
			(layers "*.Cu" "*.Mask")
			(remove_unused_layers no)
			(net "PHY_SCC_A_TO_DRV_A_32_DP")
			(clearance 0.127)
			(thermal_gap 0.127)
		)
		(pad "3" thru_hole circle
			(at 0.5715 0)
			(size 0.508 0.508)
			(drill 0.254)
			(layers "*.Cu" "*.Mask")
			(remove_unused_layers no)
			(net "PHY_SCC_A_TO_DRV_A_32_DN")
			(clearance 0.127)
			(thermal_gap 0.127)
		)
		(pad "4" thru_hole circle
			(at 1.5875 0)
			(size 0.508 0.508)
			(drill 0.254)
			(layers "*.Cu" "*.Mask")
			(remove_unused_layers no)
			(net "GND")
			(clearance 0.127)
			(thermal_gap 0.127)
		)
	)
	(footprint ""
		(layer "F.Cu")
		(at 223.839024 -347.4593 180)
		(property "Reference" "C4"
			(at 0 0 180)
			(layer "F.SilkS")
			(hide yes)
			(effects
				(font
					(size 1.27 1.27)
				)
			)
		)
		(property "Value" "SC1U16V3KX-5GP"
			(at 0 -2.8194 180)
			(unlocked yes)
			(layer "F.Fab")
			(hide yes)
			(effects
				(font
					(size 1.016 1.016)
					(thickness 0.1524)
				)
			)
		)
		(property "Device Type" "C603H36"
			(at 0 -4.3434 180)
			(unlocked yes)
			(layer "F.Fab")
			(hide yes)
			(effects
				(font
					(size 1.016 1.016)
					(thickness 0.1524)
				)
			)
		)
		(duplicate_pad_numbers_are_jumpers no)
		(fp_line
			(start 0.508 0)
			(end -0.508 0)
			(stroke
				(width 0.2032)
				(type default)
			)
			(layer "F.SilkS")
		)
		(fp_rect
			(start -0.5842 1.3335)
			(end 0.5842 -1.3335)
			(stroke
				(width 0)
				(type default)
			)
			(fill no)
			(layer "F.CrtYd")
		)
		(fp_rect
			(start -0.5842 1.3335)
			(end 0.5842 -1.3335)
			(stroke
				(width 0)
				(type default)
			)
			(fill no)
			(layer "F.Fab")
		)
		(pad "1" smd custom
			(at 0 -0.762 180)
			(size 0.2159 0.2159)
			(layers "F.Cu" "F.Mask" "F.Paste")
			(net "P3V3_STBY_A")
			(options
				(clearance outline)
				(anchor circle)
			)
			(primitives
				(gr_poly
					(pts
						(arc
							(start -0.3302 -0.4318)
							(mid -0.402042 -0.402042)
							(end -0.4318 -0.3302)
						)
						(arc
							(start -0.4318 0.3302)
							(mid -0.402042 0.402042)
							(end -0.3302 0.4318)
						)
						(arc
							(start 0.3302 0.4318)
							(mid 0.402042 0.402042)
							(end 0.4318 0.3302)
						)
						(arc
							(start 0.4318 -0.3302)
							(mid 0.402042 -0.402042)
							(end 0.3302 -0.4318)
						)
					)
					(width 0)
					(fill yes)
				)
			)
		)
		(pad "2" smd custom
			(at 0 0.762 180)
			(size 0.2159 0.2159)
			(layers "F.Cu" "F.Mask" "F.Paste")
			(net "GND")
			(options
				(clearance outline)
				(anchor circle)
			)
			(primitives
				(gr_poly
					(pts
						(arc
							(start -0.3302 -0.4318)
							(mid -0.402042 -0.402042)
							(end -0.4318 -0.3302)
						)
						(arc
							(start -0.4318 0.3302)
							(mid -0.402042 0.402042)
							(end -0.3302 0.4318)
						)
						(arc
							(start 0.3302 0.4318)
							(mid 0.402042 0.402042)
							(end 0.4318 0.3302)
						)
						(arc
							(start 0.4318 -0.3302)
							(mid 0.402042 -0.402042)
							(end 0.3302 -0.4318)
						)
					)
					(width 0)
					(fill yes)
				)
			)
		)
	)
	(footprint ""
		(layer "F.Cu")
		(at 242.189 -395.2748 180)
		(property "Reference" "C591"
			(at 0 0 180)
			(layer "F.SilkS")
			(hide yes)
			(effects
				(font
					(size 1.27 1.27)
				)
			)
		)
		(property "Value" "SC1U16V3KX-5GP"
			(at 0 -2.8194 180)
			(unlocked yes)
			(layer "F.Fab")
			(hide yes)
			(effects
				(font
					(size 1.016 1.016)
					(thickness 0.1524)
				)
			)
		)
		(property "Device Type" "C603H36"
			(at 0 -4.3434 180)
			(unlocked yes)
			(layer "F.Fab")
			(hide yes)
			(effects
				(font
					(size 1.016 1.016)
					(thickness 0.1524)
				)
			)
		)
		(duplicate_pad_numbers_are_jumpers no)
		(fp_line
			(start 0.508 0)
			(end -0.508 0)
			(stroke
				(width 0.2032)
				(type default)
			)
			(layer "F.SilkS")
		)
		(fp_rect
			(start -0.5842 1.3335)
			(end 0.5842 -1.3335)
			(stroke
				(width 0)
				(type default)
			)
			(fill no)
			(layer "F.CrtYd")
		)
		(fp_rect
			(start -0.5842 1.3335)
			(end 0.5842 -1.3335)
			(stroke
				(width 0)
				(type default)
			)
			(fill no)
			(layer "F.Fab")
		)
		(pad "1" smd custom
			(at 0 -0.762 180)
			(size 0.2159 0.2159)
			(layers "F.Cu" "F.Mask" "F.Paste")
			(net "MB3_VCAP_R")
			(options
				(clearance outline)
				(anchor circle)
			)
			(primitives
				(gr_poly
					(pts
						(arc
							(start -0.3302 -0.4318)
							(mid -0.402042 -0.402042)
							(end -0.4318 -0.3302)
						)
						(arc
							(start -0.4318 0.3302)
							(mid -0.402042 0.402042)
							(end -0.3302 0.4318)
						)
						(arc
							(start 0.3302 0.4318)
							(mid 0.402042 0.402042)
							(end 0.4318 0.3302)
						)
						(arc
							(start 0.4318 -0.3302)
							(mid 0.402042 -0.402042)
							(end 0.3302 -0.4318)
						)
					)
					(width 0)
					(fill yes)
				)
			)
		)
		(pad "2" smd custom
			(at 0 0.762 180)
			(size 0.2159 0.2159)
			(layers "F.Cu" "F.Mask" "F.Paste")
			(net "AGND_CURRENT_DPB")
			(options
				(clearance outline)
				(anchor circle)
			)
			(primitives
				(gr_poly
					(pts
						(arc
							(start -0.3302 -0.4318)
							(mid -0.402042 -0.402042)
							(end -0.4318 -0.3302)
						)
						(arc
							(start -0.4318 0.3302)
							(mid -0.402042 0.402042)
							(end -0.3302 0.4318)
						)
						(arc
							(start 0.3302 0.4318)
							(mid 0.402042 0.402042)
							(end 0.4318 0.3302)
						)
						(arc
							(start 0.4318 -0.3302)
							(mid 0.402042 -0.402042)
							(end 0.3302 -0.4318)
						)
					)
					(width 0)
					(fill yes)
				)
			)
		)
	)
	(footprint ""
		(layer "F.Cu")
		(at 346.680028 -127.254)
		(property "Reference" "R323"
			(at 0 0 0)
			(layer "F.SilkS")
			(hide yes)
			(effects
				(font
					(size 1.27 1.27)
				)
			)
		)
		(property "Value" "91R3F-1-GP"
			(at -0.0254 -2.5146 0)
			(unlocked yes)
			(layer "F.Fab")
			(hide yes)
			(effects
				(font
					(size 1.016 1.016)
					(thickness 0.1524)
				)
			)
		)
		(property "Device Type" "R603H22"
			(at -0.0254 -4.0386 0)
			(unlocked yes)
			(layer "F.Fab")
			(hide yes)
			(effects
				(font
					(size 1.016 1.016)
					(thickness 0.1524)
				)
			)
		)
		(duplicate_pad_numbers_are_jumpers no)
		(fp_line
			(start -0.4826 0)
			(end -0.2032 0)
			(stroke
				(width 0.2032)
				(type default)
			)
			(layer "F.SilkS")
		)
		(fp_line
			(start 0.2032 0)
			(end 0.4826 0)
			(stroke
				(width 0.2032)
				(type default)
			)
			(layer "F.SilkS")
		)
		(fp_rect
			(start -0.5842 1.3335)
			(end 0.5842 -1.3335)
			(stroke
				(width 0)
				(type default)
			)
			(fill no)
			(layer "F.CrtYd")
		)
		(fp_rect
			(start -0.5842 1.3335)
			(end 0.5842 -1.3335)
			(stroke
				(width 0)
				(type default)
			)
			(fill no)
			(layer "F.Fab")
		)
		(pad "1" smd custom
			(at 0 -0.762)
			(size 0.2159 0.2159)
			(layers "F.Cu" "F.Mask" "F.Paste")
			(net "P5V_A_3")
			(options
				(clearance outline)
				(anchor circle)
			)
			(primitives
				(gr_poly
					(pts
						(arc
							(start -0.3302 -0.4318)
							(mid -0.402042 -0.402042)
							(end -0.4318 -0.3302)
						)
						(arc
							(start -0.4318 0.3302)
							(mid -0.402042 0.402042)
							(end -0.3302 0.4318)
						)
						(arc
							(start 0.3302 0.4318)
							(mid 0.402042 0.402042)
							(end 0.4318 0.3302)
						)
						(arc
							(start 0.4318 -0.3302)
							(mid 0.402042 -0.402042)
							(end 0.3302 -0.4318)
						)
					)
					(width 0)
					(fill yes)
				)
			)
		)
		(pad "2" smd custom
			(at 0 0.762)
			(size 0.2159 0.2159)
			(layers "F.Cu" "F.Mask" "F.Paste")
			(net "DRV_ACT_19")
			(options
				(clearance outline)
				(anchor circle)
			)
			(primitives
				(gr_poly
					(pts
						(arc
							(start -0.3302 -0.4318)
							(mid -0.402042 -0.402042)
							(end -0.4318 -0.3302)
						)
						(arc
							(start -0.4318 0.3302)
							(mid -0.402042 0.402042)
							(end -0.3302 0.4318)
						)
						(arc
							(start 0.3302 0.4318)
							(mid 0.402042 0.402042)
							(end 0.4318 0.3302)
						)
						(arc
							(start 0.4318 -0.3302)
							(mid 0.402042 -0.402042)
							(end 0.3302 -0.4318)
						)
					)
					(width 0)
					(fill yes)
				)
			)
		)
	)
	(footprint ""
		(layer "F.Cu")
		(at 226.278694 -371.134894)
		(property "Reference" "U18"
			(at 0 0 0)
			(layer "F.SilkS")
			(hide yes)
			(effects
				(font
					(size 1.27 1.27)
				)
			)
		)
		(property "Value" "TCA9555PWR-GP"
			(at 0 -6.9342 0)
			(unlocked yes)
			(layer "F.Fab")
			(hide yes)
			(effects
				(font
					(size 1.016 1.016)
					(thickness 0.1524)
				)
			)
		)
		(property "Device Type" "TSOIC24H48"
			(at 0 -8.5852 0)
			(unlocked yes)
			(layer "F.Fab")
			(hide yes)
			(effects
				(font
					(size 1.016 1.016)
					(thickness 0.1524)
				)
			)
		)
		(duplicate_pad_numbers_are_jumpers no)
		(fp_line
			(start -4.2291 -1.397)
			(end 3.81 -1.397)
			(stroke
				(width 0.1524)
				(type default)
			)
			(layer "F.SilkS")
		)
		(fp_line
			(start -4.2291 -0.8001)
			(end -3.429 0)
			(stroke
				(width 0.1524)
				(type default)
			)
			(layer "F.SilkS")
		)
		(fp_line
			(start -4.2291 3.937)
			(end -4.2291 -1.397)
			(stroke
				(width 0.1524)
				(type default)
			)
			(layer "F.SilkS")
		)
		(fp_line
			(start -4.22656 3.81)
			(end -4.2291 1.397)
			(stroke
				(width 0.508)
				(type default)
			)
			(layer "F.SilkS")
		)
		(fp_line
			(start -3.429 0)
			(end -4.2291 0.8001)
			(stroke
				(width 0.1524)
				(type default)
			)
			(layer "F.SilkS")
		)
		(fp_line
			(start 3.81 -1.397)
			(end 3.81 1.397)
			(stroke
				(width 0.1524)
				(type default)
			)
			(layer "F.SilkS")
		)
		(fp_line
			(start 3.81 1.397)
			(end -4.2291 1.397)
			(stroke
				(width 0.1524)
				(type default)
			)
			(layer "F.SilkS")
		)
		(fp_poly
			(pts
				(xy -3.90652 -1.8542) (xy 3.90652 -1.8542) (xy 3.90652 1.8542) (xy -3.90652 1.8542)
			)
			(stroke
				(width 0)
				(type default)
			)
			(fill yes)
			(layer "F.SilkS")
		)
		(fp_poly
			(pts
				(xy -4.2164 3.81) (xy 4.2164 3.81) (xy 4.22656 -3.81) (xy -4.2164 -3.81)
			)
			(stroke
				(width 0)
				(type default)
			)
			(fill no)
			(layer "F.CrtYd")
		)
		(fp_poly
			(pts
				(xy -4.22656 -3.81) (xy 4.22656 -3.81) (xy 4.22656 3.81) (xy -4.22656 3.81)
			)
			(stroke
				(width 0)
				(type default)
			)
			(fill no)
			(layer "F.Fab")
		)
		(pad "1" smd rect
			(at -3.57632 2.8194)
			(size 0.3556 1.524)
			(layers "F.Cu" "F.Mask" "F.Paste")
			(net "IO_EXP3_HDD_FAULT_INT_N")
		)
		(pad "2" smd rect
			(at -2.92608 2.8194)
			(size 0.3556 1.524)
			(layers "F.Cu" "F.Mask" "F.Paste")
			(net "IO_EXP3_HDD_FAULT_A1")
		)
		(pad "3" smd rect
			(at -2.27584 2.8194)
			(size 0.3556 1.524)
			(layers "F.Cu" "F.Mask" "F.Paste")
			(net "IO_EXP3_HDD_FAULT_A2")
		)
		(pad "4" smd rect
			(at -1.6256 2.8194)
			(size 0.3556 1.524)
			(layers "F.Cu" "F.Mask" "F.Paste")
			(net "DRIVE_B_24_FLT_LED")
		)
		(pad "5" smd rect
			(at -0.97536 2.8194)
			(size 0.3556 1.524)
			(layers "F.Cu" "F.Mask" "F.Paste")
			(net "DRIVE_B_25_FLT_LED")
		)
		(pad "6" smd rect
			(at -0.32512 2.8194)
			(size 0.3556 1.524)
			(layers "F.Cu" "F.Mask" "F.Paste")
			(net "DRIVE_B_26_FLT_LED")
		)
		(pad "7" smd rect
			(at 0.32512 2.8194)
			(size 0.3556 1.524)
			(layers "F.Cu" "F.Mask" "F.Paste")
			(net "DRIVE_B_27_FLT_LED")
		)
		(pad "8" smd rect
			(at 0.97536 2.8194)
			(size 0.3556 1.524)
			(layers "F.Cu" "F.Mask" "F.Paste")
			(net "DRIVE_B_28_FLT_LED")
		)
		(pad "9" smd rect
			(at 1.6256 2.8194)
			(size 0.3556 1.524)
			(layers "F.Cu" "F.Mask" "F.Paste")
			(net "DRIVE_B_29_FLT_LED")
		)
		(pad "10" smd rect
			(at 2.27584 2.8194)
			(size 0.3556 1.524)
			(layers "F.Cu" "F.Mask" "F.Paste")
			(net "DRIVE_B_30_FLT_LED")
		)
		(pad "11" smd rect
			(at 2.92608 2.8194)
			(size 0.3556 1.524)
			(layers "F.Cu" "F.Mask" "F.Paste")
			(net "DRIVE_B_31_FLT_LED")
		)
		(pad "12" smd rect
			(at 3.57632 2.8194)
			(size 0.3556 1.524)
			(layers "F.Cu" "F.Mask" "F.Paste")
			(net "GND")
		)
		(pad "13" smd rect
			(at 3.57632 -2.8194)
			(size 0.3556 1.524)
			(layers "F.Cu" "F.Mask" "F.Paste")
			(net "DRIVE_B_32_FLT_LED")
		)
		(pad "14" smd rect
			(at 2.92608 -2.8194)
			(size 0.3556 1.524)
			(layers "F.Cu" "F.Mask" "F.Paste")
			(net "DRIVE_B_33_FLT_LED")
		)
		(pad "15" smd rect
			(at 2.27584 -2.8194)
			(size 0.3556 1.524)
			(layers "F.Cu" "F.Mask" "F.Paste")
			(net "DRIVE_B_34_FLT_LED")
		)
		(pad "16" smd rect
			(at 1.6256 -2.8194)
			(size 0.3556 1.524)
			(layers "F.Cu" "F.Mask" "F.Paste")
			(net "DRIVE_B_35_FLT_LED")
		)
		(pad "17" smd rect
			(at 0.97536 -2.8194)
			(size 0.3556 1.524)
			(layers "F.Cu" "F.Mask" "F.Paste")
			(net "Net_1194")
		)
		(pad "18" smd rect
			(at 0.32512 -2.8194)
			(size 0.3556 1.524)
			(layers "F.Cu" "F.Mask" "F.Paste")
			(net "Net_1193")
		)
		(pad "19" smd rect
			(at -0.32512 -2.8194)
			(size 0.3556 1.524)
			(layers "F.Cu" "F.Mask" "F.Paste")
			(net "Net_1192")
		)
		(pad "20" smd rect
			(at -0.97536 -2.8194)
			(size 0.3556 1.524)
			(layers "F.Cu" "F.Mask" "F.Paste")
			(net "Net_246")
		)
		(pad "21" smd rect
			(at -1.6256 -2.8194)
			(size 0.3556 1.524)
			(layers "F.Cu" "F.Mask" "F.Paste")
			(net "IO_EXP3_HDD_FAULT_A0")
		)
		(pad "22" smd rect
			(at -2.27584 -2.8194)
			(size 0.3556 1.524)
			(layers "F.Cu" "F.Mask" "F.Paste")
			(net "IO_EXP3_LED_SCL")
		)
		(pad "23" smd rect
			(at -2.92608 -2.8194)
			(size 0.3556 1.524)
			(layers "F.Cu" "F.Mask" "F.Paste")
			(net "IO_EXP3_LED_SDA")
		)
		(pad "24" smd rect
			(at -3.57632 -2.8194)
			(size 0.3556 1.524)
			(layers "F.Cu" "F.Mask" "F.Paste")
			(net "P3V3_STBY_B")
		)
	)
)
